(kicad_pcb
	(version 20240108)
	(generator "pcbnew")
	(generator_version "8.0")
	(general
		(thickness 1.62)
		(legacy_teardrops no)
	)
	(paper "A4")
	(title_block
		(title "Jetson Orin Baseboard")
		(date "2025-03-12")
		(rev "1.3.4")
		(company "Antmicro Ltd")
		(comment 1 "www.antmicro.com")
		(comment 9 "footprints 15-18 of 677")
	)
	(layers
		(0 "F.Cu" signal)
		(1 "In1.Cu" signal)
		(2 "In2.Cu" signal)
		(3 "In3.Cu" signal)
		(4 "In4.Cu" jumper)
		(5 "In5.Cu" signal)
		(6 "In6.Cu" signal)
		(31 "B.Cu" signal)
		(32 "B.Adhes" user "B.Adhesive")
		(33 "F.Adhes" user "F.Adhesive")
		(34 "B.Paste" user)
		(35 "F.Paste" user)
		(36 "B.SilkS" user "B.Silkscreen")
		(37 "F.SilkS" user "F.Silkscreen")
		(38 "B.Mask" user)
		(39 "F.Mask" user)
		(40 "Dwgs.User" user "User.Drawings")
		(41 "Cmts.User" user "User.Comments")
		(42 "Eco1.User" user "User.Eco1")
		(43 "Eco2.User" user "User.Eco2")
		(44 "Edge.Cuts" user)
		(45 "Margin" user)
		(46 "B.CrtYd" user "B.Courtyard")
		(47 "F.CrtYd" user "F.Courtyard")
		(48 "B.Fab" user)
		(49 "F.Fab" user)
	)
	(footprint "antmicro-footprints:R_Array_4x0402"
		(layer "F.Cu")
		(at 137.4 97.72 90)
		(property "Reference" "R53"
			(at -1.13 -0.9 90)
			(layer "F.SilkS")
			(effects
				(font
					(size 0.7 0.7)
					(thickness 0.15)
				)
				(justify left bottom)
			)
		)
		(property "Value" "R_4x330R_0402_array"
			(at -1.5 2 90)
			(layer "F.Fab")
			(effects
				(font
					(size 0.7 0.7)
					(thickness 0.15)
				)
				(justify left bottom)
			)
		)
		(property "Footprint" "antmicro-footprints:R_Array_4x0402"
			(at 0 0 90)
			(layer "F.Fab")
			(hide yes)
			(effects
				(font
					(size 1.27 1.27)
					(thickness 0.15)
				)
			)
		)
		(property "Datasheet" "http://industrial.panasonic.com/cdbs/www-data/pdf/AOC0000/AOC0000C14.pdf"
			(at 0 0 90)
			(layer "F.Fab")
			(hide yes)
			(effects
				(font
					(size 1.27 1.27)
					(thickness 0.15)
				)
			)
		)
		(property "Author" "Antmicro"
			(at 235.12 -39.68 0)
			(layer "F.Fab")
			(hide yes)
			(effects
				(font
					(size 1 1)
					(thickness 0.15)
				)
			)
		)
		(property "License" "Apache-2.0"
			(at 235.12 -39.68 0)
			(layer "F.Fab")
			(hide yes)
			(effects
				(font
					(size 1 1)
					(thickness 0.15)
				)
			)
		)
		(property "MPN" "EXB-28V331JX"
			(at 235.12 -39.68 0)
			(layer "F.Fab")
			(hide yes)
			(effects
				(font
					(size 1 1)
					(thickness 0.15)
				)
			)
		)
		(property "Manufacturer" "Panasonic"
			(at 235.12 -39.68 0)
			(layer "F.Fab")
			(hide yes)
			(effects
				(font
					(size 1 1)
					(thickness 0.15)
				)
			)
		)
		(property "Val" "R_4x330R_0402"
			(at 235.12 -39.68 0)
			(layer "F.Fab")
			(hide yes)
			(effects
				(font
					(size 1 1)
					(thickness 0.15)
				)
			)
		)
		(sheetname "Peripherals")
		(sheetfile "peripherals.kicad_sch")
		(attr smd)
		(fp_line
			(start -1.17 -0.5)
			(end -1.17 0.498)
			(stroke
				(width 0.15)
				(type solid)
			)
			(layer "F.SilkS")
		)
		(fp_line
			(start 1.167 0.498)
			(end 1.167 -0.5)
			(stroke
				(width 0.15)
				(type solid)
			)
			(layer "F.SilkS")
		)
		(fp_rect
			(start -1.2 -0.9)
			(end 1.2 0.9)
			(stroke
				(width 0.05)
				(type solid)
			)
			(fill none)
			(layer "F.CrtYd")
		)
		(fp_line
			(start 0.998 -0.5)
			(end 0.998 0.498)
			(stroke
				(width 0.15)
				(type solid)
			)
			(layer "F.Fab")
		)
		(fp_line
			(start -1 -0.5)
			(end 0.998 -0.5)
			(stroke
				(width 0.15)
				(type solid)
			)
			(layer "F.Fab")
		)
		(fp_line
			(start 0.998 0.498)
			(end -1 0.498)
			(stroke
				(width 0.15)
				(type solid)
			)
			(layer "F.Fab")
		)
		(fp_line
			(start -1 0.498)
			(end -1 -0.5)
			(stroke
				(width 0.15)
				(type solid)
			)
			(layer "F.Fab")
		)
		(fp_text user "${REFERENCE}"
			(at -1.5 3.25 90)
			(layer "F.Fab")
			(hide yes)
			(effects
				(font
					(size 0.7 0.7)
					(thickness 0.15)
				)
				(justify left bottom)
			)
		)
		(fp_text user "License: Apache-2.0"
			(at -1.5 5.75 90)
			(layer "F.Fab")
			(hide yes)
			(effects
				(font
					(size 0.7 0.7)
					(thickness 0.15)
				)
				(justify left bottom)
			)
		)
		(fp_text user "Author: Antmicro"
			(at -1.5 4.5 90)
			(layer "F.Fab")
			(hide yes)
			(effects
				(font
					(size 0.7 0.7)
					(thickness 0.15)
				)
				(justify left bottom)
			)
		)
		(pad "1" smd roundrect
			(at -0.802 0.45 90)
			(size 0.4 0.5)
			(layers "F.Cu" "F.Paste" "F.Mask")
			(roundrect_rratio 0.25)
			(net 584 "/Peripherals/UART1_RXD_CONN")
			(pinfunction "R1.1")
			(pintype "passive")
		)
		(pad "2" smd roundrect
			(at -0.272 0.45 90)
			(size 0.4 0.5)
			(layers "F.Cu" "F.Paste" "F.Mask")
			(roundrect_rratio 0.25)
			(net 579 "/Peripherals/GPIO09_CONN")
			(pinfunction "R2.1")
			(pintype "passive")
		)
		(pad "3" smd roundrect
			(at 0.27 0.45 90)
			(size 0.4 0.5)
			(layers "F.Cu" "F.Paste" "F.Mask")
			(roundrect_rratio 0.25)
			(net 637 "unconnected-(R53-R3.1-Pad3)")
			(pinfunction "R3.1")
			(pintype "passive+no_connect")
		)
		(pad "4" smd roundrect
			(at 0.8 0.45 90)
			(size 0.4 0.5)
			(layers "F.Cu" "F.Paste" "F.Mask")
			(roundrect_rratio 0.25)
			(net 638 "unconnected-(R53-R4.1-Pad4)")
			(pinfunction "R4.1")
			(pintype "passive+no_connect")
		)
		(pad "5" smd roundrect
			(at 0.8 -0.452 90)
			(size 0.4 0.5)
			(layers "F.Cu" "F.Paste" "F.Mask")
			(roundrect_rratio 0.25)
			(net 640 "unconnected-(R53-R4.2-Pad5)")
			(pinfunction "R4.2")
			(pintype "passive+no_connect")
		)
		(pad "6" smd roundrect
			(at 0.27 -0.452 90)
			(size 0.4 0.5)
			(layers "F.Cu" "F.Paste" "F.Mask")
			(roundrect_rratio 0.25)
			(net 645 "unconnected-(R53-R3.2-Pad6)")
			(pinfunction "R3.2")
			(pintype "passive+no_connect")
		)
		(pad "7" smd roundrect
			(at -0.272 -0.452 90)
			(size 0.4 0.5)
			(layers "F.Cu" "F.Paste" "F.Mask")
			(roundrect_rratio 0.25)
			(net 78 "GPIO09")
			(pinfunction "R2.2")
			(pintype "passive")
		)
		(pad "8" smd roundrect
			(at -0.802 -0.452 90)
			(size 0.4 0.5)
			(layers "F.Cu" "F.Paste" "F.Mask")
			(roundrect_rratio 0.25)
			(net 461 "UART1_RXD")
			(pinfunction "R1.2")
			(pintype "passive")
		)
	)
	(footprint "antmicro-footprints:USON-10_2.5x1mm_P0.5mm"
		(layer "F.Cu")
		(at 72 115.5 90)
		(descr "USON-10 2.5x1mm_ Pitch 0.5mm")
		(tags "USON-10 2.5x1mm Pitch 0.5mm")
		(property "Reference" "U15"
			(at 0.85 -1.55 180)
			(layer "F.SilkS")
			(effects
				(font
					(size 0.7 0.7)
					(thickness 0.15)
				)
				(justify left bottom)
			)
		)
		(property "Value" "TPD4E05U06QDQARQ1"
			(at 0.018 2.499 90)
			(layer "F.Fab")
			(effects
				(font
					(size 0.7 0.7)
					(thickness 0.15)
				)
				(justify left bottom)
			)
		)
		(property "Footprint" "antmicro-footprints:USON-10_2.5x1mm_P0.5mm"
			(at 0 0 90)
			(layer "F.Fab")
			(hide yes)
			(effects
				(font
					(size 1.27 1.27)
					(thickness 0.15)
				)
			)
		)
		(property "Datasheet" "https://www.ti.com/lit/ds/symlink/tpd4e05u06-q1.pdf?HQS=dis-mous-null-mousermode-dsf-pf-null-wwe&ts=1663591265741&ref_url=https%253A%252F%252Fwww.mouser.com%252F"
			(at 0 0 90)
			(layer "F.Fab")
			(hide yes)
			(effects
				(font
					(size 1.27 1.27)
					(thickness 0.15)
				)
			)
		)
		(property "Author" "Antmicro"
			(at 187.5 43.5 0)
			(layer "F.Fab")
			(hide yes)
			(effects
				(font
					(size 1 1)
					(thickness 0.15)
				)
			)
		)
		(property "License" "Apache-2.0"
			(at 187.5 43.5 0)
			(layer "F.Fab")
			(hide yes)
			(effects
				(font
					(size 1 1)
					(thickness 0.15)
				)
			)
		)
		(property "MPN" "TPD4E05U06QDQARQ1"
			(at 187.5 43.5 0)
			(layer "F.Fab")
			(hide yes)
			(effects
				(font
					(size 1 1)
					(thickness 0.15)
				)
			)
		)
		(property "Manufacturer" "Texas Instruments"
			(at 187.5 43.5 0)
			(layer "F.Fab")
			(hide yes)
			(effects
				(font
					(size 1 1)
					(thickness 0.15)
				)
			)
		)
		(sheetname "USB Debug, DP")
		(sheetfile "usb.kicad_sch")
		(attr smd)
		(fp_line
			(start 0.498 -1.401)
			(end -0.5 -1.401)
			(stroke
				(width 0.15)
				(type solid)
			)
			(layer "F.SilkS")
		)
		(fp_line
			(start 0.498 1.398)
			(end -0.5 1.398)
			(stroke
				(width 0.15)
				(type solid)
			)
			(layer "F.SilkS")
		)
		(fp_circle
			(center -0.68 -1.27)
			(end -0.63 -1.27)
			(stroke
				(width 0.15)
				(type solid)
			)
			(fill solid)
			(layer "F.SilkS")
		)
		(fp_rect
			(start -0.8 -1.5)
			(end 0.8 1.499)
			(stroke
				(width 0.05)
				(type solid)
			)
			(fill none)
			(layer "F.CrtYd")
		)
		(fp_line
			(start 0.498 -1.25)
			(end -0.25 -1.25)
			(stroke
				(width 0.15)
				(type solid)
			)
			(layer "F.Fab")
		)
		(fp_line
			(start 0.498 -1.25)
			(end 0.498 1.249)
			(stroke
				(width 0.15)
				(type solid)
			)
			(layer "F.Fab")
		)
		(fp_line
			(start -0.25 -1.25)
			(end -0.5 -1)
			(stroke
				(width 0.15)
				(type solid)
			)
			(layer "F.Fab")
		)
		(fp_line
			(start -0.5 -1)
			(end -0.5 1.249)
			(stroke
				(width 0.15)
				(type solid)
			)
			(layer "F.Fab")
		)
		(fp_line
			(start -0.5 1.249)
			(end 0.498 1.249)
			(stroke
				(width 0.15)
				(type solid)
			)
			(layer "F.Fab")
		)
		(fp_text user "${REFERENCE}"
			(at -0.802 4.498 90)
			(layer "F.Fab")
			(hide yes)
			(effects
				(font
					(size 0.7 0.7)
					(thickness 0.15)
				)
				(justify left bottom)
			)
		)
		(fp_text user "Author: Antmicro"
			(at -0.802 5.7 90)
			(layer "F.Fab")
			(hide yes)
			(effects
				(font
					(size 0.7 0.7)
					(thickness 0.15)
				)
				(justify left bottom)
			)
		)
		(fp_text user "License: Apache-2.0"
			(at -0.802 6.9 90)
			(layer "F.Fab")
			(hide yes)
			(effects
				(font
					(size 0.7 0.7)
					(thickness 0.15)
				)
				(justify left bottom)
			)
		)
		(pad "1" smd roundrect
			(at -0.387 -1)
			(size 0.25 0.55)
			(layers "F.Cu" "F.Paste" "F.Mask")
			(roundrect_rratio 0.25)
			(net 154 "/USB Debug, DP/USBC0_RX1_P")
			(pintype "passive")
		)
		(pad "2" smd roundrect
			(at -0.387 -0.5)
			(size 0.25 0.55)
			(layers "F.Cu" "F.Paste" "F.Mask")
			(roundrect_rratio 0.25)
			(net 152 "/USB Debug, DP/USBC0_RX1_N")
			(pintype "passive")
		)
		(pad "3" smd roundrect
			(at -0.387 0)
			(size 0.4 0.55)
			(layers "F.Cu" "F.Paste" "F.Mask")
			(roundrect_rratio 0.25)
			(net 1 "GND")
			(pintype "power_in")
		)
		(pad "4" smd roundrect
			(at -0.387 0.498)
			(size 0.25 0.55)
			(layers "F.Cu" "F.Paste" "F.Mask")
			(roundrect_rratio 0.25)
			(net 258 "/USB Debug, DP/USBC0_CONN_TX1_P")
			(pintype "passive")
		)
		(pad "5" smd roundrect
			(at -0.387 0.998)
			(size 0.25 0.55)
			(layers "F.Cu" "F.Paste" "F.Mask")
			(roundrect_rratio 0.25)
			(net 198 "/USB Debug, DP/USBC0_CONN_TX1_N")
			(pintype "passive")
		)
		(pad "6" smd roundrect
			(at 0.385 0.998)
			(size 0.25 0.55)
			(layers "F.Cu" "F.Paste" "F.Mask")
			(roundrect_rratio 0.25)
			(net 198 "/USB Debug, DP/USBC0_CONN_TX1_N")
			(pintype "passive")
		)
		(pad "7" smd roundrect
			(at 0.385 0.498)
			(size 0.25 0.55)
			(layers "F.Cu" "F.Paste" "F.Mask")
			(roundrect_rratio 0.25)
			(net 258 "/USB Debug, DP/USBC0_CONN_TX1_P")
			(pintype "passive")
		)
		(pad "8" smd roundrect
			(at 0.385 0)
			(size 0.4 0.55)
			(layers "F.Cu" "F.Paste" "F.Mask")
			(roundrect_rratio 0.25)
			(net 1 "GND")
			(pintype "passive")
		)
		(pad "9" smd roundrect
			(at 0.385 -0.5)
			(size 0.25 0.55)
			(layers "F.Cu" "F.Paste" "F.Mask")
			(roundrect_rratio 0.25)
			(net 152 "/USB Debug, DP/USBC0_RX1_N")
			(pintype "passive")
		)
		(pad "10" smd roundrect
			(at 0.385 -1)
			(size 0.25 0.55)
			(layers "F.Cu" "F.Paste" "F.Mask")
			(roundrect_rratio 0.25)
			(net 154 "/USB Debug, DP/USBC0_RX1_P")
			(pintype "passive")
		)
	)
	(footprint "antmicro-footprints:R_0603_1608Metric"
		(layer "F.Cu")
		(at 143.85 119.3)
		(descr "Resistor SMD 0603")
		(tags "resistor SMD 0603")
		(property "Reference" "R248"
			(at -2.75 1.5 0)
			(layer "F.SilkS")
			(effects
				(font
					(size 0.7 0.7)
					(thickness 0.15)
				)
				(justify left bottom)
			)
		)
		(property "Value" "R_0R_22.4A_0603"
			(at 0 1.6 0)
			(layer "F.Fab")
			(effects
				(font
					(size 0.7 0.7)
					(thickness 0.15)
				)
				(justify left bottom)
			)
		)
		(property "Footprint" "antmicro-footprints:R_0603_1608Metric"
			(at 0 0 0)
			(layer "F.Fab")
			(hide yes)
			(effects
				(font
					(size 1.27 1.27)
					(thickness 0.15)
				)
			)
		)
		(property "Datasheet" "https://fscdn.rohm.com/en/products/databook/datasheet/passive/resistor/chip_resistor/pmr-jpw-e.pdf"
			(at 0 0 0)
			(layer "F.Fab")
			(hide yes)
			(effects
				(font
					(size 1.27 1.27)
					(thickness 0.15)
				)
			)
		)
		(property "Author" "Antmicro"
			(at 0 0 0)
			(layer "F.Fab")
			(hide yes)
			(effects
				(font
					(size 1 1)
					(thickness 0.15)
				)
			)
		)
		(property "License" "Apache-2.0"
			(at 0 0 0)
			(layer "F.Fab")
			(hide yes)
			(effects
				(font
					(size 1 1)
					(thickness 0.15)
				)
			)
		)
		(property "MPN" "PMR03EZPJ000"
			(at 0 0 0)
			(layer "F.Fab")
			(hide yes)
			(effects
				(font
					(size 1 1)
					(thickness 0.15)
				)
			)
		)
		(property "Manufacturer" "ROHM Semiconductor"
			(at 0 0 0)
			(layer "F.Fab")
			(hide yes)
			(effects
				(font
					(size 1 1)
					(thickness 0.15)
				)
			)
		)
		(property "Max. Curr." "22.4A"
			(at 0 0 0)
			(layer "F.Fab")
			(hide yes)
			(effects
				(font
					(size 1 1)
					(thickness 0.15)
				)
			)
		)
		(property "Tolerance" "template_tolerance"
			(at 0 0 0)
			(layer "F.Fab")
			(hide yes)
			(effects
				(font
					(size 1 1)
					(thickness 0.15)
				)
			)
		)
		(property "Val" "0R"
			(at 0 0 0)
			(layer "F.Fab")
			(hide yes)
			(effects
				(font
					(size 1 1)
					(thickness 0.15)
				)
			)
		)
		(sheetname "Peripherals")
		(sheetfile "peripherals.kicad_sch")
		(attr smd)
		(fp_line
			(start -0.15 -0.4)
			(end 0.15 -0.4)
			(stroke
				(width 0.15)
				(type solid)
			)
			(layer "F.SilkS")
		)
		(fp_line
			(start -0.15 0.4)
			(end 0.15 0.4)
			(stroke
				(width 0.15)
				(type solid)
			)
			(layer "F.SilkS")
		)
		(fp_rect
			(start -1.25 -0.65)
			(end 1.25 0.65)
			(stroke
				(width 0.05)
				(type solid)
			)
			(fill none)
			(layer "F.CrtYd")
		)
		(fp_rect
			(start -0.8 -0.4)
			(end 0.8 0.4)
			(stroke
				(width 0.15)
				(type solid)
			)
			(fill none)
			(layer "F.Fab")
		)
		(fp_text user "${REFERENCE}"
			(at -1.25 3.898 0)
			(layer "F.Fab")
			(hide yes)
			(effects
				(font
					(size 0.7 0.7)
					(thickness 0.15)
				)
				(justify left bottom)
			)
		)
		(fp_text user "License: Apache-2.0"
			(at -1.25 5.9 0)
			(layer "F.Fab")
			(hide yes)
			(effects
				(font
					(size 0.7 0.7)
					(thickness 0.15)
				)
				(justify left bottom)
			)
		)
		(fp_text user "Author: Antmicro"
			(at -1.25 4.9 0)
			(layer "F.Fab")
			(hide yes)
			(effects
				(font
					(size 0.7 0.7)
					(thickness 0.15)
				)
				(justify left bottom)
			)
		)
		(pad "1" smd roundrect
			(at -0.7 0)
			(size 0.8 1)
			(layers "F.Cu" "F.Paste" "F.Mask")
			(roundrect_rratio 0.2)
			(net 115 "VCC")
			(pintype "passive")
		)
		(pad "2" smd roundrect
			(at 0.7 0)
			(size 0.8 1)
			(layers "F.Cu" "F.Paste" "F.Mask")
			(roundrect_rratio 0.2)
			(net 485 "/Peripherals/VCC_CONN")
			(pintype "passive")
		)
	)
	(footprint "antmicro-footprints:R_0402_1005Metric"
		(layer "F.Cu")
		(at 100.05 114.65 -90)
		(descr "Resistor SMD 0402")
		(tags "resistor SMD 0402")
		(property "Reference" "R232"
			(at -0.8 -0.45 -90)
			(layer "F.SilkS")
			(effects
				(font
					(size 0.7 0.7)
					(thickness 0.15)
				)
				(justify left bottom)
			)
		)
		(property "Value" "R_10k_0402"
			(at 0 1.4 -90)
			(layer "F.Fab")
			(effects
				(font
					(size 0.7 0.7)
					(thickness 0.15)
				)
				(justify left bottom)
			)
		)
		(property "Footprint" "antmicro-footprints:R_0402_1005Metric"
			(at 0 0 -90)
			(layer "F.Fab")
			(hide yes)
			(effects
				(font
					(size 1.27 1.27)
					(thickness 0.15)
				)
			)
		)
		(property "Datasheet" "https://www.bourns.com/docs/product-datasheets/cr.pdf"
			(at 0 0 -90)
			(layer "F.Fab")
			(hide yes)
			(effects
				(font
					(size 1.27 1.27)
					(thickness 0.15)
				)
			)
		)
		(property "Author" "Antmicro"
			(at -14.6 214.7 0)
			(layer "F.Fab")
			(hide yes)
			(effects
				(font
					(size 1 1)
					(thickness 0.15)
				)
			)
		)
		(property "License" "Apache-2.0"
			(at -14.6 214.7 0)
			(layer "F.Fab")
			(hide yes)
			(effects
				(font
					(size 1 1)
					(thickness 0.15)
				)
			)
		)
		(property "MPN" "CR0402-FX-1002GLF"
			(at -14.6 214.7 0)
			(layer "F.Fab")
			(hide yes)
			(effects
				(font
					(size 1 1)
					(thickness 0.15)
				)
			)
		)
		(property "Manufacturer" "Bourns"
			(at -14.6 214.7 0)
			(layer "F.Fab")
			(hide yes)
			(effects
				(font
					(size 1 1)
					(thickness 0.15)
				)
			)
		)
		(property "Tolerance" "1%"
			(at -14.6 214.7 0)
			(layer "F.Fab")
			(hide yes)
			(effects
				(font
					(size 1 1)
					(thickness 0.15)
				)
			)
		)
		(property "Val" "10k"
			(at -14.6 214.7 0)
			(layer "F.Fab")
			(hide yes)
			(effects
				(font
					(size 1 1)
					(thickness 0.15)
				)
			)
		)
		(sheetname "Peripherals")
		(sheetfile "peripherals.kicad_sch")
		(attr smd)
		(fp_rect
			(start -0.925 -0.47)
			(end 0.925 0.47)
			(stroke
				(width 0.05)
				(type default)
			)
			(fill none)
			(layer "F.CrtYd")
		)
		(fp_rect
			(start -0.5 -0.25)
			(end 0.5 0.25)
			(stroke
				(width 0.15)
				(type solid)
			)
			(fill none)
			(layer "F.Fab")
		)
		(fp_text user "Author: Antmicro"
			(at -0.95 4.169 -90)
			(layer "F.Fab")
			(hide yes)
			(effects
				(font
					(size 0.7 0.7)
					(thickness 0.15)
				)
				(justify left bottom)
			)
		)
		(fp_text user "${REFERENCE}"
			(at -0.95 3.168 -90)
			(layer "F.Fab")
			(hide yes)
			(effects
				(font
					(size 0.7 0.7)
					(thickness 0.15)
				)
				(justify left bottom)
			)
		)
		(fp_text user "License: Apache-2.0"
			(at -0.95 5.169 -90)
			(layer "F.Fab")
			(hide yes)
			(effects
				(font
					(size 0.7 0.7)
					(thickness 0.15)
				)
				(justify left bottom)
			)
		)
		(pad "1" smd roundrect
			(at -0.48 0 270)
			(size 0.59 0.64)
			(layers "F.Cu" "F.Paste" "F.Mask")
			(roundrect_rratio 0.25)
			(net 45 "USER_BTN0")
			(pintype "passive")
		)
		(pad "2" smd roundrect
			(at 0.48 0 270)
			(size 0.59 0.64)
			(layers "F.Cu" "F.Paste" "F.Mask")
			(roundrect_rratio 0.25)
			(net 112 "+1V8")
			(pintype "passive")
		)
	)
)
